# T6G (Grand Teton) — schematic parts with pin connectivity, parts 2627–2627 of 8303; source: Cadence DE-HDL packaged netlist (pstxprt.dat, pstxnet.dat, pstchip.dat)

J67  SCONN288_DDR506112002KQ  IO  pkg DDR288S_1-1VXC  page 97
  1  VIN_BULK0  POWER  = P12V_MEM_CPU0
  2  RFU0  TRI  = NC
  3  VIN_MGMT  POWER  = P3V3_AUX
  4  HSCL  IN  = I3C_SPD_DDRL_CPU0_SCL
  5  HSDA  BI  = I3C_SPD_DDRL_CPU0_SDA
  6  VSS0  POWER  = GND
  7  DQ0_A  BI  = M_L_CPU0_SA_DQ<0>
  8  VSS1  POWER  = GND
  9  DQ1_A  BI  = M_L_CPU0_SA_DQ<1>
  10  VSS2  POWER  = GND
  11  DQS0_A_T  BI  = M_L_CPU0_SA_DQS_DP<0>
  12  DQS0_A_C  BI  = M_L_CPU0_SA_DQS_DN<0>
  13  VSS3  POWER  = GND
  14  DQ4_A  BI  = M_L_CPU0_SA_DQ<4>
  15  VSS4  POWER  = GND
  16  DQ5_A  BI  = M_L_CPU0_SA_DQ<5>
  17  VSS5  POWER  = GND
  18  DQ8_A  BI  = M_L_CPU0_SA_DQ<8>
  19  VSS6  POWER  = GND
  20  DQ9_A  BI  = M_L_CPU0_SA_DQ<9>
  21  VSS7  POWER  = GND
  22  DQS1_A_T  BI  = M_L_CPU0_SA_DQS_DP<1>
  23  DQS1_A_C  BI  = M_L_CPU0_SA_DQS_DN<1>
  24  VSS8  POWER  = GND
  25  DQ12_A  BI  = M_L_CPU0_SA_DQ<12>
  26  VSS9  POWER  = GND
  27  DQ13_A  BI  = M_L_CPU0_SA_DQ<13>
  28  VSS10  POWER  = GND
  29  DQ16_A  BI  = M_L_CPU0_SA_DQ<16>
  30  VSS11  POWER  = GND
  31  DQ17_A  BI  = M_L_CPU0_SA_DQ<17>
  32  VSS12  POWER  = GND
  33  DQS2_A_T  BI  = M_L_CPU0_SA_DQS_DP<2>
  34  DQS2_A_C  BI  = M_L_CPU0_SA_DQS_DN<2>
  35  VSS13  POWER  = GND
  36  DQ20_A  BI  = M_L_CPU0_SA_DQ<20>
  37  VSS14  POWER  = GND
  38  DQ21_A  BI  = M_L_CPU0_SA_DQ<21>
  39  VSS15  POWER  = GND
  40  DQ24_A  BI  = M_L_CPU0_SA_DQ<24>
  41  VSS16  POWER  = GND
  42  DQ25_A  BI  = M_L_CPU0_SA_DQ<25>
  43  VSS17  POWER  = GND
  44  DQS3_A_T  BI  = M_L_CPU0_SA_DQS_DP<3>
  45  DQS3_A_C  BI  = M_L_CPU0_SA_DQS_DN<3>
  46  VSS18  POWER  = GND
  47  DQ28_A  BI  = M_L_CPU0_SA_DQ<28>
  48  VSS19  POWER  = GND
  49  DQ29_A  BI  = M_L_CPU0_SA_DQ<29>
  50  VSS20  POWER  = GND
  51  CB0_A  BI  = M_L_CPU0_SA_CB<0>
  52  VSS21  POWER  = GND
  53  CB1_A  BI  = M_L_CPU0_SA_CB<1>
  54  VSS22  POWER  = GND
  55  DQS4_A_T  BI  = M_L_CPU0_SA_DQS_DP<4>
  56  DQS4_A_C  BI  = M_L_CPU0_SA_DQS_DN<4>
  57  VSS23  POWER  = GND
  58  CB4_A  BI  = M_L_CPU0_SA_CB<4>
  59  VSS24  POWER  = GND
  60  CB5_A  BI  = M_L_CPU0_SA_CB<5>
  61  VSS25  POWER  = GND
  62  ALERT_N  OUT  = M_L_CPU0_ALERT_N
  63  VSS26  POWER  = GND
  64  CS0_A_N  IN  = M_L_CPU0_SA_CS_N<0>
  65  VSS27  POWER  = GND
  66  CA0_A  IN  = M_L_CPU0_SA_CA<0>
  67  VSS28  POWER  = GND
  68  CA2_A  IN  = M_L_CPU0_SA_CA<2>
  69  VSS29  POWER  = GND
  70  CA4_A  IN  = M_L_CPU0_SA_CA<4>
  71  VSS30  POWER  = GND
  72  CA6_A  IN  = M_L_CPU0_SA_CA<6>
  73  VSS31  POWER  = GND
  74  PAR_A  IN  = M_L_CPU0_SA_PAR
  75  VSS32  POWER  = GND
  76  CA0_B  IN  = M_L_CPU0_SB_CA<0>
  77  VSS33  POWER  = GND
  78  CA2_B  IN  = M_L_CPU0_SB_CA<2>
  79  VSS34  POWER  = GND
  80  CA4_B  IN  = M_L_CPU0_SB_CA<4>
  81  VSS35  POWER  = GND
  82  CA6_B  IN  = M_L_CPU0_SB_CA<6>
  83  VSS36  POWER  = GND
  84  CS0_B_N  IN  = M_L_CPU0_SB_CS_N<0>
  85  VSS37  POWER  = GND
  86  \lbd||rsp_a_n\  OUT  = M_L_CPU0_SA_RSP<0>
  87  \lbs||rsp_b_n\  OUT  = M_L_CPU0_SB_RSP<0>
  88  VSS38  POWER  = GND
  89  CB4_B  BI  = M_L_CPU0_SB_CB<4>
  90  VSS39  POWER  = GND
  91  CB5_B  BI  = M_L_CPU0_SB_CB<5>
  92  VSS40  POWER  = GND
  93  \dqs9_b_t||tdqs9_b_t||dbi4_b_n\  BI  = M_L_CPU0_SB_DQS_DP<9>
  94  \dqs9_b_c||tdqs9_b_c\  BI  = M_L_CPU0_SB_DQS_DN<9>
  95  VSS41  POWER  = GND
  96  CB0_B  BI  = M_L_CPU0_SB_CB<0>
  97  VSS42  POWER  = GND
  98  CB1_B  BI  = M_L_CPU0_SB_CB<1>
  99  VSS43  POWER  = GND
  100  DQ0_B  BI  = M_L_CPU0_SB_DQ<0>
  101  VSS44  POWER  = GND
  102  DQ1_B  BI  = M_L_CPU0_SB_DQ<1>
  103  VSS45  POWER  = GND
  104  DQS0_B_T  BI  = M_L_CPU0_SB_DQS_DP<0>
  105  DQS0_B_C  BI  = M_L_CPU0_SB_DQS_DN<0>
  106  VSS46  POWER  = GND
  107  DQ4_B  BI  = M_L_CPU0_SB_DQ<4>
  108  VSS47  POWER  = GND
  109  DQ5_B  BI  = M_L_CPU0_SB_DQ<5>
  110  VSS48  POWER  = GND
  111  DQ8_B  BI  = M_L_CPU0_SB_DQ<8>
  112  VSS49  POWER  = GND
  113  DQ9_B  BI  = M_L_CPU0_SB_DQ<9>
  114  VSS50  POWER  = GND
  115  DQS1_B_T  BI  = M_L_CPU0_SB_DQS_DP<1>
  116  DQS1_B_C  BI  = M_L_CPU0_SB_DQS_DN<1>
  117  VSS51  POWER  = GND
  118  DQ12_B  BI  = M_L_CPU0_SB_DQ<12>
  119  VSS52  POWER  = GND
  120  DQ13_B  BI  = M_L_CPU0_SB_DQ<13>
  121  VSS53  POWER  = GND
  122  DQ16_B  BI  = M_L_CPU0_SB_DQ<16>
  123  VSS54  POWER  = GND
  124  DQ17_B  BI  = M_L_CPU0_SB_DQ<17>
  125  VSS55  POWER  = GND
  126  DQS2_B_T  BI  = M_L_CPU0_SB_DQS_DP<2>
  127  DQS2_B_C  BI  = M_L_CPU0_SB_DQS_DN<2>
  128  VSS56  POWER  = GND
  129  DQ20_B  BI  = M_L_CPU0_SB_DQ<20>
  130  VSS57  POWER  = GND
  131  DQ21_B  BI  = M_L_CPU0_SB_DQ<21>
  132  VSS58  POWER  = GND
  133  DQ24_B  BI  = M_L_CPU0_SB_DQ<24>
  134  VSS59  POWER  = GND
  135  DQ25_B  BI  = M_L_CPU0_SB_DQ<25>
  136  VSS60  POWER  = GND
  137  DQS3_B_T  BI  = M_L_CPU0_SB_DQS_DP<3>
  138  DQS3_B_C  BI  = M_L_CPU0_SB_DQS_DN<3>
  139  VSS61  POWER  = GND
  140  DQ28_B  BI  = M_L_CPU0_SB_DQ<28>
  141  VSS62  POWER  = GND
  142  DQ29_B  BI  = M_L_CPU0_SB_DQ<29>
  143  VSS63  POWER  = GND
  144  RFU1  TRI  = NC
  145  VIN_BULK1  POWER  = P12V_MEM_CPU0
  146  VIN_BULK2  POWER  = P12V_MEM_CPU0
  147  \pwr_good||fail_n\  BI  = PWRGD_CHL_CPU0_DIMM
  148  HAS  IN  = PD_CHL_CPU0_DIMM_SAA
  149  RFU2  TRI  = NC
  150  RFU3  TRI  = NC
  151  VSS64  POWER  = GND
  152  DQ2_A  BI  = M_L_CPU0_SA_DQ<2>
  153  VSS65  POWER  = GND
  154  DQ3_A  BI  = M_L_CPU0_SA_DQ<3>
  155  VSS66  POWER  = GND
  156  \dqs5_a_c||tdqs5_a_c||dqs5_a_t||tdqs5_a_t\  BI  = M_L_CPU0_SA_DQS_DN<5>
  157  \dqs5_a_t||tdqs5_a_t\  BI  = M_L_CPU0_SA_DQS_DP<5>
  158  VSS67  POWER  = GND
  159  DQ6_A  BI  = M_L_CPU0_SA_DQ<6>
  160  VSS68  POWER  = GND
  161  DQ7_A  BI  = M_L_CPU0_SA_DQ<7>
  162  VSS69  POWER  = GND
  163  DQ10_A  BI  = M_L_CPU0_SA_DQ<10>
  164  VSS70  POWER  = GND
  165  DQ11_A  BI  = M_L_CPU0_SA_DQ<11>
  166  VSS71  POWER  = GND
  167  \dqs6_a_c||tdqs6_a_c||dqs6_a_t||tdqs6_a_t\  BI  = M_L_CPU0_SA_DQS_DN<6>
  168  \dqs6_a_t||tdqs6_a_t\  BI  = M_L_CPU0_SA_DQS_DP<6>
  169  VSS72  POWER  = GND
  170  DQ14_A  BI  = M_L_CPU0_SA_DQ<14>
  171  VSS73  POWER  = GND
  172  DQ15_A  BI  = M_L_CPU0_SA_DQ<15>
  173  VSS74  POWER  = GND
  174  DQ18_A  BI  = M_L_CPU0_SA_DQ<18>
  175  VSS75  POWER  = GND
  176  DQ19_A  BI  = M_L_CPU0_SA_DQ<19>
  177  VSS76  POWER  = GND
  178  \dqs7_a_c||tdqs7_a_c\  BI  = M_L_CPU0_SA_DQS_DN<7>
  179  \dqs7_a_t||tdqs7_a_t\  BI  = M_L_CPU0_SA_DQS_DP<7>
  180  VSS77  POWER  = GND
  181  DQ22_A  BI  = M_L_CPU0_SA_DQ<22>
  182  VSS78  POWER  = GND
  183  DQ23_A  BI  = M_L_CPU0_SA_DQ<23>
  184  VSS79  POWER  = GND
  185  DQ26_A  BI  = M_L_CPU0_SA_DQ<26>
  186  VSS80  POWER  = GND
  187  DQ27_A  BI  = M_L_CPU0_SA_DQ<27>
  188  VSS81  POWER  = GND
  189  \dqs8_a_c||tdqs8_a_c\  BI  = M_L_CPU0_SA_DQS_DN<8>
  190  \dqs8_a_t||tdqs8_a_t\  BI  = M_L_CPU0_SA_DQS_DP<8>
  191  VSS82  POWER  = GND
  192  DQ30_A  BI  = M_L_CPU0_SA_DQ<30>
  193  VSS83  POWER  = GND
  194  DQ31_A  BI  = M_L_CPU0_SA_DQ<31>
  195  VSS84  POWER  = GND
  196  CB2_A  BI  = M_L_CPU0_SA_CB<2>
  197  VSS85  POWER  = GND
  198  CB3_A  BI  = M_L_CPU0_SA_CB<3>
  199  VSS86  POWER  = GND
  200  \dqs9_a_c||tdqs9_a_c\  BI  = M_L_CPU0_SA_DQS_DN<9>
  201  \dqs9_a_t||tdqs9_a_t\  BI  = M_L_CPU0_SA_DQS_DP<9>
  202  VSS87  POWER  = GND
  203  CB6_A  BI  = M_L_CPU0_SA_CB<6>
  204  VSS88  POWER  = GND
  205  CB7_A  BI  = M_L_CPU0_SA_CB<7>
  206  VSS89  POWER  = GND
  207  RESET_N  IN  = M_L_CPU0_RESET_N
  208  VSS90  POWER  = GND
  209  CS1_A_N  IN  = M_L_CPU0_SA_CS_N<1>
  210  VSS91  POWER  = GND
  211  CA1_A  IN  = M_L_CPU0_SA_CA<1>
  212  VSS92  POWER  = GND
  213  CA3_A  IN  = M_L_CPU0_SA_CA<3>
  214  VSS93  POWER  = GND
  215  CA5_A  IN  = M_L_CPU0_SA_CA<5>
  216  VSS94  POWER  = GND
  217  CK_T  IN  = M_L_CPU0_CLK_DP<0>
  218  CK_C  IN  = M_L_CPU0_CLK_DN<0>
  219  VSS95  POWER  = GND
  220  RFU4  TRI  = NC
  221  CA1_B  IN  = M_L_CPU0_SB_CA<1>
  222  VSS96  POWER  = GND
  223  CA3_B  IN  = M_L_CPU0_SB_CA<3>
  224  VSS97  POWER  = GND
  225  CA5_B  IN  = M_L_CPU0_SB_CA<5>
  226  VSS98  POWER  = GND
  227  PAR_B  IN  = M_L_CPU0_SB_PAR
  228  VSS99  POWER  = GND
  229  CS1_B_N  IN  = M_L_CPU0_SB_CS_N<1>
  230  VSS100  POWER  = GND
  231  RFU5  TRI  = NC
  232  RFU6  TRI  = NC
  233  VSS101  POWER  = GND
  234  CB6_B  BI  = M_L_CPU0_SB_CB<6>
  235  VSS102  POWER  = GND
  236  CB7_B  BI  = M_L_CPU0_SB_CB<7>
  237  VSS103  POWER  = GND
  238  DQS4_B_C  BI  = M_L_CPU0_SB_DQS_DN<4>
  239  DQS4_B_T  BI  = M_L_CPU0_SB_DQS_DP<4>
  240  VSS104  POWER  = GND
  241  CB2_B  BI  = M_L_CPU0_SB_CB<2>
  242  VSS105  POWER  = GND
  243  CB3_B  BI  = M_L_CPU0_SB_CB<3>
  244  VSS106  POWER  = GND
  245  DQ2_B  BI  = M_L_CPU0_SB_DQ<2>
  246  VSS107  POWER  = GND
  247  DQ3_B  BI  = M_L_CPU0_SB_DQ<3>
  248  VSS108  POWER  = GND
  249  \dqs5_b_c||tdqs5_b_c\  BI  = M_L_CPU0_SB_DQS_DN<5>
  250  \dqs5_b_t||tdqs5_b_t\  BI  = M_L_CPU0_SB_DQS_DP<5>
  251  VSS109  POWER  = GND
  252  DQ6_B  BI  = M_L_CPU0_SB_DQ<6>
  253  VSS110  POWER  = GND
  254  DQ7_B  BI  = M_L_CPU0_SB_DQ<7>
  255  VSS111  POWER  = GND
  256  DQ10_B  BI  = M_L_CPU0_SB_DQ<10>
  257  VSS112  POWER  = GND
  258  DQ11_B  BI  = M_L_CPU0_SB_DQ<11>
  259  VSS113  POWER  = GND
  260  \dqs6_b_c||tdqs6_b_c\  BI  = M_L_CPU0_SB_DQS_DN<6>
  261  \dqs6_b_t||tdqs6_b_t\  BI  = M_L_CPU0_SB_DQS_DP<6>
  262  VSS114  POWER  = GND
  263  DQ14_B  BI  = M_L_CPU0_SB_DQ<14>
  264  VSS115  POWER  = GND
  265  DQ15_B  BI  = M_L_CPU0_SB_DQ<15>
  266  VSS116  POWER  = GND
  267  DQ18_B  BI  = M_L_CPU0_SB_DQ<18>
  268  VSS117  POWER  = GND
  269  DQ19_B  BI  = M_L_CPU0_SB_DQ<19>
  270  VSS118  POWER  = GND
  271  \dqs7_b_c||tdqs7_b_c\  BI  = M_L_CPU0_SB_DQS_DN<7>
  272  \dqs7_b_t||tdqs7_b_t\  BI  = M_L_CPU0_SB_DQS_DP<7>
  273  VSS119  POWER  = GND
  274  DQ22_B  BI  = M_L_CPU0_SB_DQ<22>
  275  VSS120  POWER  = GND
  276  DQ23_B  BI  = M_L_CPU0_SB_DQ<23>
  277  VSS121  POWER  = GND
  278  DQ26_B  BI  = M_L_CPU0_SB_DQ<26>
  279  VSS122  POWER  = GND
  280  DQ27_B  BI  = M_L_CPU0_SB_DQ<27>
  281  VSS123  POWER  = GND
  282  \dqs8_b_c||tdqs8_b_c\  BI  = M_L_CPU0_SB_DQS_DN<8>
  283  \dqs8_b_t||tdqs8_b_t\  BI  = M_L_CPU0_SB_DQS_DP<8>
  284  VSS124  POWER  = GND
  285  DQ30_B  BI  = M_L_CPU0_SB_DQ<30>
  286  VSS125  POWER  = GND
  287  DQ31_B  BI  = M_L_CPU0_SB_DQ<31>
  288  VSS126  POWER  = GND
  G1  G1  POWER  = GND
  G2  G2  POWER  = GND
  G3  G3  POWER  = GND
